# S9S_MB_2U (Grand Teton) — schematic netlist excerpt (pin names and nets, part order shuffled) for the footprints in the layout excerpt that follows; sources: Cadence DE-HDL packaged netlist, KiCad conversion of 03242023_DA0F0TMBIJ0_F0T_Motherboard_J_brd_V01_OCP.brd

C1904  Q_CAP  0.01UF 50V 10% X7R  pkg C0402  page 217 : A = P3V3_AUX_FPGA_VCCIO5 ; B = GND
PR2520  Q_RES  1 1% EMPTY  pkg 0402LF  page 304 : A = P12V_HSC_SENSE2_P ; B = P12V_HSC_SENSE2_R1_P

(kicad_pcb
	(version 20260206)
	(generator "pcbnew")
	(generator_version "10.0")
	(general
		(thickness 1.6)
		(legacy_teardrops no)
	)
	(paper "A4")
	(title_block
		(title "03242023_DA0F0TMBIJ0_F0T_Motherboard_J_brd_V01_OCP.brd")
		(comment 1 "Grand Teton / footprints 4308-4309 of 6105")
	)
	(layers
		(0 "F.Cu" signal "TOP")
		(4 "In1.Cu" signal "GND")
		(6 "In2.Cu" signal "IN1")
		(8 "In3.Cu" signal "GND1")
		(10 "In4.Cu" signal "IN2")
		(12 "In5.Cu" signal "GND2")
		(14 "In6.Cu" signal "IN3")
		(16 "In7.Cu" signal "GND3")
		(18 "In8.Cu" signal "VCC")
		(20 "In9.Cu" signal "VCC1")
		(22 "In10.Cu" signal "GND4")
		(24 "In11.Cu" signal "IN4")
		(26 "In12.Cu" signal "GND5")
		(28 "In13.Cu" signal "IN5")
		(30 "In14.Cu" signal "GND6")
		(32 "In15.Cu" signal "IN6")
		(34 "In16.Cu" signal "GND7")
		(2 "B.Cu" signal "BOTTOM")
		(9 "F.Adhes" user "F.Adhesive")
		(11 "B.Adhes" user "B.Adhesive")
		(13 "F.Paste" user "Package Geometry/Pastemask Top")
		(15 "B.Paste" user "Package Geometry/Pastemask Bottom")
		(5 "F.SilkS" user "Ref Des/Silkscreen Top")
		(7 "B.SilkS" user "Ref Des/Silkscreen Bottom")
		(1 "F.Mask" user "Board Geometry/Soldermask Top")
		(3 "B.Mask" user "Board Geometry/Soldermask Bottom")
		(17 "Dwgs.User" user "User.Drawings")
		(19 "Cmts.User" user "User.Comments")
		(21 "Eco1.User" user "User.Eco1")
		(23 "Eco2.User" user "User.Eco2")
		(25 "Edge.Cuts" user "Board Geometry/Outline")
		(27 "Margin" user)
		(31 "F.CrtYd" user "Package Geometry/Place Bound Top")
		(29 "B.CrtYd" user "Package Geometry/Place Bound Bottom")
		(35 "F.Fab" user "Ref Des/Assembly Top")
		(33 "B.Fab" user "Ref Des/Assembly Bottom")
	)
	(footprint ""
		(layer "B.Cu")
		(at 177.355754 -110.975394 -90)
		(property "Reference" "C1904"
			(at 0 0 90)
			(layer "B.SilkS")
			(hide yes)
			(effects
				(font
					(size 1.27 1.27)
				)
				(justify mirror)
			)
		)
		(property "Value" ""
			(at 0 0 90)
			(layer "B.Fab")
			(effects
				(font
					(size 1.27 1.27)
				)
				(justify mirror)
			)
		)
		(duplicate_pad_numbers_are_jumpers no)
		(fp_line
			(start -0.69215 0.2921)
			(end 0.69215 0.2921)
			(stroke
				(width 0.1524)
				(type default)
			)
			(layer "B.SilkS")
		)
		(fp_line
			(start 0.69215 0.2921)
			(end 0.69215 -0.2921)
			(stroke
				(width 0.1524)
				(type default)
			)
			(layer "B.SilkS")
		)
		(fp_line
			(start -0.69215 -0.2921)
			(end -0.69215 0.2921)
			(stroke
				(width 0.1524)
				(type default)
			)
			(layer "B.SilkS")
		)
		(fp_line
			(start 0.69215 -0.2921)
			(end -0.69215 -0.2921)
			(stroke
				(width 0.1524)
				(type default)
			)
			(layer "B.SilkS")
		)
		(fp_line
			(start -0.51435 0.2794)
			(end 0.51435 0.2794)
			(stroke
				(width 0.1)
				(type default)
			)
			(layer "B.Fab")
		)
		(fp_line
			(start 0.51435 0.2794)
			(end 0.51435 -0.2794)
			(stroke
				(width 0.1)
				(type default)
			)
			(layer "B.Fab")
		)
		(fp_line
			(start -0.51435 -0.2794)
			(end -0.51435 0.2794)
			(stroke
				(width 0.1)
				(type default)
			)
			(layer "B.Fab")
		)
		(fp_line
			(start 0.51435 -0.2794)
			(end -0.51435 -0.2794)
			(stroke
				(width 0.1)
				(type default)
			)
			(layer "B.Fab")
		)
		(pad "1" smd circle
			(at 0.40005 0 90)
			(size 0 0)
			(layers "B.Cu" "B.Mask" "B.Paste")
			(net "P3V3_AUX_FPGA_VCCIO5")
		)
		(pad "2" smd circle
			(at -0.40005 0 90)
			(size 0 0)
			(layers "B.Cu" "B.Mask" "B.Paste")
			(net "GND")
		)
		(zone
			(layer "B.Cu")
			(hatch none 0.5)
			(connect_pads
				(clearance 0)
			)
			(min_thickness 0.25)
			(keepout
				(tracks not_allowed)
				(vias allowed)
				(pads allowed)
				(copperpour not_allowed)
				(footprints allowed)
			)
			(placement
				(enabled no)
				(sheetname "")
			)
			(fill
				(thermal_gap 0.5)
				(thermal_bridge_width 0.5)
				(island_removal_mode 0)
			)
			(polygon
				(pts
					(xy 177.268124 -110.784894) (xy 177.209958 -110.876334) (xy 177.209958 -111.075724) (xy 177.268124 -111.165894)
					(xy 177.443384 -111.165894) (xy 177.501804 -111.075724) (xy 177.501804 -110.876334) (xy 177.443638 -110.784894)
				)
			)
		)
	)
	(footprint ""
		(layer "B.Cu")
		(at 298.47413 -400.999452 -90)
		(property "Reference" "PR2520"
			(at 0 0 90)
			(layer "B.SilkS")
			(hide yes)
			(effects
				(font
					(size 1.27 1.27)
				)
				(justify mirror)
			)
		)
		(property "Value" ""
			(at 0 0 90)
			(layer "B.Fab")
			(effects
				(font
					(size 1.27 1.27)
				)
				(justify mirror)
			)
		)
		(duplicate_pad_numbers_are_jumpers no)
		(fp_line
			(start -0.7874 0.4064)
			(end 0.7874 0.4064)
			(stroke
				(width 0.1524)
				(type default)
			)
			(layer "B.SilkS")
		)
		(fp_line
			(start 0.7874 0.4064)
			(end 0.7874 -0.4064)
			(stroke
				(width 0.1524)
				(type default)
			)
			(layer "B.SilkS")
		)
		(fp_line
			(start -0.7874 -0.4064)
			(end -0.7874 0.4064)
			(stroke
				(width 0.1524)
				(type default)
			)
			(layer "B.SilkS")
		)
		(fp_line
			(start 0.7874 -0.4064)
			(end -0.7874 -0.4064)
			(stroke
				(width 0.1524)
				(type default)
			)
			(layer "B.SilkS")
		)
		(fp_line
			(start -0.67945 0.3048)
			(end -0.120396 0.3048)
			(stroke
				(width 0.1)
				(type default)
			)
			(layer "B.Fab")
		)
		(fp_line
			(start -0.120396 0.3048)
			(end -0.120396 0.2794)
			(stroke
				(width 0.1)
				(type default)
			)
			(layer "B.Fab")
		)
		(fp_line
			(start 0.12065 0.3048)
			(end 0.67945 0.3048)
			(stroke
				(width 0.1)
				(type default)
			)
			(layer "B.Fab")
		)
		(fp_line
			(start 0.67945 0.3048)
			(end 0.67945 -0.305054)
			(stroke
				(width 0.1)
				(type default)
			)
			(layer "B.Fab")
		)
		(fp_line
			(start -0.120396 0.2794)
			(end 0.12065 0.2794)
			(stroke
				(width 0.1)
				(type default)
			)
			(layer "B.Fab")
		)
		(fp_line
			(start 0.12065 0.2794)
			(end 0.12065 0.3048)
			(stroke
				(width 0.1)
				(type default)
			)
			(layer "B.Fab")
		)
		(fp_line
			(start -0.12065 -0.2794)
			(end -0.12065 -0.3048)
			(stroke
				(width 0.1)
				(type default)
			)
			(layer "B.Fab")
		)
		(fp_line
			(start 0.12065 -0.2794)
			(end -0.12065 -0.2794)
			(stroke
				(width 0.1)
				(type default)
			)
			(layer "B.Fab")
		)
		(fp_line
			(start -0.67945 -0.3048)
			(end -0.67945 0.3048)
			(stroke
				(width 0.1)
				(type default)
			)
			(layer "B.Fab")
		)
		(fp_line
			(start -0.12065 -0.3048)
			(end -0.67945 -0.3048)
			(stroke
				(width 0.1)
				(type default)
			)
			(layer "B.Fab")
		)
		(fp_line
			(start 0.12065 -0.305054)
			(end 0.12065 -0.2794)
			(stroke
				(width 0.1)
				(type default)
			)
			(layer "B.Fab")
		)
		(fp_line
			(start 0.67945 -0.305054)
			(end 0.12065 -0.305054)
			(stroke
				(width 0.1)
				(type default)
			)
			(layer "B.Fab")
		)
		(pad "1" smd circle
			(at 0.40005 0 90)
			(size 0 0)
			(layers "B.Cu" "B.Mask" "B.Paste")
			(net "P12V_HSC_SENSE2_P")
		)
		(pad "2" smd circle
			(at -0.40005 0 90)
			(size 0 0)
			(layers "B.Cu" "B.Mask" "B.Paste")
			(net "P12V_HSC_SENSE2_R1_P")
		)
	)
)
